FILE_TYPE = MULTI_PHYS_TABLE;
PART 'SCONN200_H68296001'
{====================================================================================================================================================================================}
:PACK_TYPE | MATERIAL  |PART_NUMBER      = EnvComp |PART_NUMBER    |JEDEC_TYPE             |CLASS    |DESCRIPTION                            |HEIGHT      |COMPONENT_TYPE    |LPID   | SPEED_URL | Status |RPL| AML | Bus_Unit | Days;
{====================================================================================================================================================================================}
'SM'       |'CONN'     |'H68296-001'(!)  = ''      |'H68296-001'   |'SCONN200_H68296001'   |'IO'     |'CONN,MISC,200P,SAMT HSEC8,VERT RCPT'  |'0.320 IN'  |'SMTCONN'         |'3840' | 'http://speed.intel.com:8081/speed/module/pdm/item/pdm_item_detail_direct.asp?item_cde=H68296-001&item_rev=01&url_param=unused' | '' | '' | '' | '' | '' 
'SM'       |'EMPTY'    |'H68296-001'(!)  = ''      |'H68296-001'   |'SCONN200_H68296001'   |'IO'     |'CONN,MISC,200P,SAMT HSEC8,VERT RCPT'  |'0.320 IN'  |'SMTCONN'         |'3840' | 'http://speed.intel.com:8081/speed/module/pdm/item/pdm_item_detail_direct.asp?item_cde=H68296-001&item_rev=01&url_param=unused' | '' | '' | '' | '' | '' 
END_PART
END.
